(kicad_pcb
	(version 20260206)
	(generator "pcbnew")
	(generator_version "10.0")
	(general
		(thickness 1.6)
		(legacy_teardrops no)
	)
	(paper "A4")
	(title_block
		(title "01162023_DA0F0TEBIF0_F0T_Expander_BD_F_brd_V02_OCP.brd")
		(comment 1 "Grand Teton / footprints 7309-7316 of 9728")
	)
	(layers
		(0 "F.Cu" signal "TOP")
		(4 "In1.Cu" signal "GND")
		(6 "In2.Cu" signal "VCC")
		(8 "In3.Cu" signal "VCC1")
		(10 "In4.Cu" signal "GND1")
		(12 "In5.Cu" signal "IN1")
		(14 "In6.Cu" signal "GND2")
		(16 "In7.Cu" signal "IN2")
		(18 "In8.Cu" signal "GND3")
		(20 "In9.Cu" signal "IN3")
		(22 "In10.Cu" signal "GND4")
		(24 "In11.Cu" signal "IN4")
		(26 "In12.Cu" signal "GND5")
		(28 "In13.Cu" signal "IN5")
		(30 "In14.Cu" signal "GND6")
		(32 "In15.Cu" signal "IN6")
		(34 "In16.Cu" signal "GND7")
		(2 "B.Cu" signal "BOTTOM")
		(9 "F.Adhes" user "F.Adhesive")
		(11 "B.Adhes" user "B.Adhesive")
		(13 "F.Paste" user "Package Geometry/Pastemask Top")
		(15 "B.Paste" user "Package Geometry/Pastemask Bottom")
		(5 "F.SilkS" user "Ref Des/Silkscreen Top")
		(7 "B.SilkS" user "Ref Des/Silkscreen Bottom")
		(1 "F.Mask" user "Board Geometry/Soldermask Top")
		(3 "B.Mask" user "Board Geometry/Soldermask Bottom")
		(17 "Dwgs.User" user "User.Drawings")
		(19 "Cmts.User" user "User.Comments")
		(21 "Eco1.User" user "User.Eco1")
		(23 "Eco2.User" user "User.Eco2")
		(25 "Edge.Cuts" user "Board Geometry/Outline")
		(27 "Margin" user)
		(31 "F.CrtYd" user "Package Geometry/Place Bound Top")
		(29 "B.CrtYd" user "Package Geometry/Place Bound Bottom")
		(35 "F.Fab" user "Ref Des/Assembly Top")
		(33 "B.Fab" user "Ref Des/Assembly Bottom")
	)
	(footprint ""
		(layer "B.Cu")
		(at 102.364032 -333.614522)
		(property "Reference" "R4228"
			(at 0 0 0)
			(layer "B.SilkS")
			(hide yes)
			(effects
				(font
					(size 1.27 1.27)
				)
				(justify mirror)
			)
		)
		(property "Value" ""
			(at 0 0 0)
			(layer "B.Fab")
			(effects
				(font
					(size 1.27 1.27)
				)
				(justify mirror)
			)
		)
		(duplicate_pad_numbers_are_jumpers no)
		(fp_line
			(start -0.7874 -0.4064)
			(end -0.7874 0.4064)
			(stroke
				(width 0.1524)
				(type default)
			)
			(layer "B.SilkS")
		)
		(fp_line
			(start -0.7874 0.4064)
			(end 0.7874 0.4064)
			(stroke
				(width 0.1524)
				(type default)
			)
			(layer "B.SilkS")
		)
		(fp_line
			(start 0.7874 -0.4064)
			(end -0.7874 -0.4064)
			(stroke
				(width 0.1524)
				(type default)
			)
			(layer "B.SilkS")
		)
		(fp_line
			(start 0.7874 0.4064)
			(end 0.7874 -0.4064)
			(stroke
				(width 0.1524)
				(type default)
			)
			(layer "B.SilkS")
		)
		(fp_line
			(start -0.67945 -0.3048)
			(end -0.67945 0.3048)
			(stroke
				(width 0.1)
				(type default)
			)
			(layer "B.Fab")
		)
		(fp_line
			(start -0.67945 0.3048)
			(end -0.120396 0.3048)
			(stroke
				(width 0.1)
				(type default)
			)
			(layer "B.Fab")
		)
		(fp_line
			(start -0.12065 -0.3048)
			(end -0.67945 -0.3048)
			(stroke
				(width 0.1)
				(type default)
			)
			(layer "B.Fab")
		)
		(fp_line
			(start -0.12065 -0.2794)
			(end -0.12065 -0.3048)
			(stroke
				(width 0.1)
				(type default)
			)
			(layer "B.Fab")
		)
		(fp_line
			(start -0.120396 0.2794)
			(end 0.12065 0.2794)
			(stroke
				(width 0.1)
				(type default)
			)
			(layer "B.Fab")
		)
		(fp_line
			(start -0.120396 0.3048)
			(end -0.120396 0.2794)
			(stroke
				(width 0.1)
				(type default)
			)
			(layer "B.Fab")
		)
		(fp_line
			(start 0.12065 -0.305054)
			(end 0.12065 -0.2794)
			(stroke
				(width 0.1)
				(type default)
			)
			(layer "B.Fab")
		)
		(fp_line
			(start 0.12065 -0.2794)
			(end -0.12065 -0.2794)
			(stroke
				(width 0.1)
				(type default)
			)
			(layer "B.Fab")
		)
		(fp_line
			(start 0.12065 0.2794)
			(end 0.12065 0.3048)
			(stroke
				(width 0.1)
				(type default)
			)
			(layer "B.Fab")
		)
		(fp_line
			(start 0.12065 0.3048)
			(end 0.67945 0.3048)
			(stroke
				(width 0.1)
				(type default)
			)
			(layer "B.Fab")
		)
		(fp_line
			(start 0.67945 -0.305054)
			(end 0.12065 -0.305054)
			(stroke
				(width 0.1)
				(type default)
			)
			(layer "B.Fab")
		)
		(fp_line
			(start 0.67945 0.3048)
			(end 0.67945 -0.305054)
			(stroke
				(width 0.1)
				(type default)
			)
			(layer "B.Fab")
		)
		(pad "1" smd circle
			(at 0.40005 0 180)
			(size 0 0)
			(layers "B.Cu" "B.Mask" "B.Paste")
			(net "PEX_REF_CLK_BUFFER_EN_N")
		)
		(pad "2" smd circle
			(at -0.40005 0 180)
			(size 0 0)
			(layers "B.Cu" "B.Mask" "B.Paste")
			(net "P3V3")
		)
	)
	(footprint ""
		(layer "B.Cu")
		(at 145.804382 -224.75063 180)
		(property "Reference" "R6167"
			(at 0 0 0)
			(layer "B.SilkS")
			(hide yes)
			(effects
				(font
					(size 1.27 1.27)
				)
				(justify mirror)
			)
		)
		(property "Value" ""
			(at 0 0 0)
			(layer "B.Fab")
			(effects
				(font
					(size 1.27 1.27)
				)
				(justify mirror)
			)
		)
		(duplicate_pad_numbers_are_jumpers no)
		(fp_line
			(start 0.7874 0.4064)
			(end 0.7874 -0.4064)
			(stroke
				(width 0.1524)
				(type default)
			)
			(layer "B.SilkS")
		)
		(fp_line
			(start 0.7874 -0.4064)
			(end -0.7874 -0.4064)
			(stroke
				(width 0.1524)
				(type default)
			)
			(layer "B.SilkS")
		)
		(fp_line
			(start -0.7874 0.4064)
			(end 0.7874 0.4064)
			(stroke
				(width 0.1524)
				(type default)
			)
			(layer "B.SilkS")
		)
		(fp_line
			(start -0.7874 -0.4064)
			(end -0.7874 0.4064)
			(stroke
				(width 0.1524)
				(type default)
			)
			(layer "B.SilkS")
		)
		(fp_line
			(start 0.67945 0.3048)
			(end 0.67945 -0.305054)
			(stroke
				(width 0.1)
				(type default)
			)
			(layer "B.Fab")
		)
		(fp_line
			(start 0.67945 -0.305054)
			(end 0.12065 -0.305054)
			(stroke
				(width 0.1)
				(type default)
			)
			(layer "B.Fab")
		)
		(fp_line
			(start 0.12065 0.3048)
			(end 0.67945 0.3048)
			(stroke
				(width 0.1)
				(type default)
			)
			(layer "B.Fab")
		)
		(fp_line
			(start 0.12065 0.2794)
			(end 0.12065 0.3048)
			(stroke
				(width 0.1)
				(type default)
			)
			(layer "B.Fab")
		)
		(fp_line
			(start 0.12065 -0.2794)
			(end -0.12065 -0.2794)
			(stroke
				(width 0.1)
				(type default)
			)
			(layer "B.Fab")
		)
		(fp_line
			(start 0.12065 -0.305054)
			(end 0.12065 -0.2794)
			(stroke
				(width 0.1)
				(type default)
			)
			(layer "B.Fab")
		)
		(fp_line
			(start -0.120396 0.3048)
			(end -0.120396 0.2794)
			(stroke
				(width 0.1)
				(type default)
			)
			(layer "B.Fab")
		)
		(fp_line
			(start -0.120396 0.2794)
			(end 0.12065 0.2794)
			(stroke
				(width 0.1)
				(type default)
			)
			(layer "B.Fab")
		)
		(fp_line
			(start -0.12065 -0.2794)
			(end -0.12065 -0.3048)
			(stroke
				(width 0.1)
				(type default)
			)
			(layer "B.Fab")
		)
		(fp_line
			(start -0.12065 -0.3048)
			(end -0.67945 -0.3048)
			(stroke
				(width 0.1)
				(type default)
			)
			(layer "B.Fab")
		)
		(fp_line
			(start -0.67945 0.3048)
			(end -0.120396 0.3048)
			(stroke
				(width 0.1)
				(type default)
			)
			(layer "B.Fab")
		)
		(fp_line
			(start -0.67945 -0.3048)
			(end -0.67945 0.3048)
			(stroke
				(width 0.1)
				(type default)
			)
			(layer "B.Fab")
		)
		(pad "1" smd circle
			(at 0.40005 0)
			(size 0 0)
			(layers "B.Cu" "B.Mask" "B.Paste")
			(net "SPI_PEX1_RST_R_N")
		)
		(pad "2" smd circle
			(at -0.40005 0)
			(size 0 0)
			(layers "B.Cu" "B.Mask" "B.Paste")
			(net "GND")
		)
	)
	(footprint ""
		(layer "B.Cu")
		(at 366.872774 -321.84594 -90)
		(property "Reference" "R6540"
			(at 0 0 90)
			(layer "B.SilkS")
			(hide yes)
			(effects
				(font
					(size 1.27 1.27)
				)
				(justify mirror)
			)
		)
		(property "Value" ""
			(at 0 0 90)
			(layer "B.Fab")
			(effects
				(font
					(size 1.27 1.27)
				)
				(justify mirror)
			)
		)
		(duplicate_pad_numbers_are_jumpers no)
		(fp_line
			(start -0.7874 0.4064)
			(end 0.7874 0.4064)
			(stroke
				(width 0.1524)
				(type default)
			)
			(layer "B.SilkS")
		)
		(fp_line
			(start 0.7874 0.4064)
			(end 0.7874 -0.4064)
			(stroke
				(width 0.1524)
				(type default)
			)
			(layer "B.SilkS")
		)
		(fp_line
			(start -0.7874 -0.4064)
			(end -0.7874 0.4064)
			(stroke
				(width 0.1524)
				(type default)
			)
			(layer "B.SilkS")
		)
		(fp_line
			(start 0.7874 -0.4064)
			(end -0.7874 -0.4064)
			(stroke
				(width 0.1524)
				(type default)
			)
			(layer "B.SilkS")
		)
		(fp_line
			(start -0.67945 0.3048)
			(end -0.120396 0.3048)
			(stroke
				(width 0.1)
				(type default)
			)
			(layer "B.Fab")
		)
		(fp_line
			(start -0.120396 0.3048)
			(end -0.120396 0.2794)
			(stroke
				(width 0.1)
				(type default)
			)
			(layer "B.Fab")
		)
		(fp_line
			(start 0.12065 0.3048)
			(end 0.67945 0.3048)
			(stroke
				(width 0.1)
				(type default)
			)
			(layer "B.Fab")
		)
		(fp_line
			(start 0.67945 0.3048)
			(end 0.67945 -0.305054)
			(stroke
				(width 0.1)
				(type default)
			)
			(layer "B.Fab")
		)
		(fp_line
			(start -0.120396 0.2794)
			(end 0.12065 0.2794)
			(stroke
				(width 0.1)
				(type default)
			)
			(layer "B.Fab")
		)
		(fp_line
			(start 0.12065 0.2794)
			(end 0.12065 0.3048)
			(stroke
				(width 0.1)
				(type default)
			)
			(layer "B.Fab")
		)
		(fp_line
			(start -0.12065 -0.2794)
			(end -0.12065 -0.3048)
			(stroke
				(width 0.1)
				(type default)
			)
			(layer "B.Fab")
		)
		(fp_line
			(start 0.12065 -0.2794)
			(end -0.12065 -0.2794)
			(stroke
				(width 0.1)
				(type default)
			)
			(layer "B.Fab")
		)
		(fp_line
			(start -0.67945 -0.3048)
			(end -0.67945 0.3048)
			(stroke
				(width 0.1)
				(type default)
			)
			(layer "B.Fab")
		)
		(fp_line
			(start -0.12065 -0.3048)
			(end -0.67945 -0.3048)
			(stroke
				(width 0.1)
				(type default)
			)
			(layer "B.Fab")
		)
		(fp_line
			(start 0.12065 -0.305054)
			(end 0.12065 -0.2794)
			(stroke
				(width 0.1)
				(type default)
			)
			(layer "B.Fab")
		)
		(fp_line
			(start 0.67945 -0.305054)
			(end 0.12065 -0.305054)
			(stroke
				(width 0.1)
				(type default)
			)
			(layer "B.Fab")
		)
		(pad "1" smd circle
			(at 0.40005 0 90)
			(size 0 0)
			(layers "B.Cu" "B.Mask" "B.Paste")
			(net "P0V8_SERDES_VDDA_PEX3")
		)
		(pad "2" smd circle
			(at -0.40005 0 90)
			(size 0 0)
			(layers "B.Cu" "B.Mask" "B.Paste")
			(net "P0V8_SERDES_VDDA_PEX3_C5")
		)
	)
	(footprint ""
		(layer "B.Cu")
		(at 187.149994 -298.27474 180)
		(property "Reference" "C3113"
			(at 0 0 0)
			(layer "B.SilkS")
			(hide yes)
			(effects
				(font
					(size 1.27 1.27)
				)
				(justify mirror)
			)
		)
		(property "Value" ""
			(at 0 0 0)
			(layer "B.Fab")
			(effects
				(font
					(size 1.27 1.27)
				)
				(justify mirror)
			)
		)
		(duplicate_pad_numbers_are_jumpers no)
		(fp_line
			(start 0.299974 0.150114)
			(end 0.299974 -0.150114)
			(stroke
				(width 0.1)
				(type default)
			)
			(layer "B.Fab")
		)
		(fp_line
			(start 0.299974 -0.150114)
			(end -0.299974 -0.150114)
			(stroke
				(width 0.1)
				(type default)
			)
			(layer "B.Fab")
		)
		(fp_line
			(start -0.299974 0.150114)
			(end 0.299974 0.150114)
			(stroke
				(width 0.1)
				(type default)
			)
			(layer "B.Fab")
		)
		(fp_line
			(start -0.299974 -0.150114)
			(end -0.299974 0.150114)
			(stroke
				(width 0.1)
				(type default)
			)
			(layer "B.Fab")
		)
		(pad "1" smd rect
			(at 0.2667 0)
			(size 0.3048 0.381)
			(layers "B.Cu" "B.Mask" "B.Paste")
			(net "P1V25_PEX1")
		)
		(pad "2" smd rect
			(at -0.2667 0)
			(size 0.3048 0.381)
			(layers "B.Cu" "B.Mask" "B.Paste")
			(net "GND")
		)
	)
	(footprint ""
		(layer "B.Cu")
		(at 237.304072 -217.104214 -90)
		(property "Reference" "C2023"
			(at 0 0 90)
			(layer "B.SilkS")
			(hide yes)
			(effects
				(font
					(size 1.27 1.27)
				)
				(justify mirror)
			)
		)
		(property "Value" ""
			(at 0 0 90)
			(layer "B.Fab")
			(effects
				(font
					(size 1.27 1.27)
				)
				(justify mirror)
			)
		)
		(duplicate_pad_numbers_are_jumpers no)
		(fp_line
			(start -0.69215 0.2921)
			(end 0.69215 0.2921)
			(stroke
				(width 0.1524)
				(type default)
			)
			(layer "B.SilkS")
		)
		(fp_line
			(start 0.69215 0.2921)
			(end 0.69215 -0.2921)
			(stroke
				(width 0.1524)
				(type default)
			)
			(layer "B.SilkS")
		)
		(fp_line
			(start -0.69215 -0.2921)
			(end -0.69215 0.2921)
			(stroke
				(width 0.1524)
				(type default)
			)
			(layer "B.SilkS")
		)
		(fp_line
			(start 0.69215 -0.2921)
			(end -0.69215 -0.2921)
			(stroke
				(width 0.1524)
				(type default)
			)
			(layer "B.SilkS")
		)
		(fp_line
			(start -0.51435 0.2794)
			(end 0.51435 0.2794)
			(stroke
				(width 0.1)
				(type default)
			)
			(layer "B.Fab")
		)
		(fp_line
			(start 0.51435 0.2794)
			(end 0.51435 -0.2794)
			(stroke
				(width 0.1)
				(type default)
			)
			(layer "B.Fab")
		)
		(fp_line
			(start -0.51435 -0.2794)
			(end -0.51435 0.2794)
			(stroke
				(width 0.1)
				(type default)
			)
			(layer "B.Fab")
		)
		(fp_line
			(start 0.51435 -0.2794)
			(end -0.51435 -0.2794)
			(stroke
				(width 0.1)
				(type default)
			)
			(layer "B.Fab")
		)
		(pad "1" smd circle
			(at 0.40005 0 90)
			(size 0 0)
			(layers "B.Cu" "B.Mask" "B.Paste")
			(net "P1V2_BIC_PLL")
		)
		(pad "2" smd circle
			(at -0.40005 0 90)
			(size 0 0)
			(layers "B.Cu" "B.Mask" "B.Paste")
			(net "GND")
		)
		(zone
			(layer "B.Cu")
			(hatch none 0.5)
			(connect_pads
				(clearance 0)
			)
			(min_thickness 0.25)
			(keepout
				(tracks not_allowed)
				(vias allowed)
				(pads allowed)
				(copperpour not_allowed)
				(footprints allowed)
			)
			(placement
				(enabled no)
				(sheetname "")
			)
			(fill
				(thermal_gap 0.5)
				(thermal_bridge_width 0.5)
				(island_removal_mode 0)
			)
			(polygon
				(pts
					(xy 237.216442 -216.913714) (xy 237.158276 -217.005154) (xy 237.158276 -217.204544) (xy 237.216442 -217.294714)
					(xy 237.391702 -217.294714) (xy 237.450122 -217.204544) (xy 237.450122 -217.005154) (xy 237.391956 -216.913714)
				)
			)
		)
	)
	(footprint ""
		(layer "B.Cu")
		(at 419.349936 -297.32478 180)
		(property "Reference" "C3440"
			(at 0 0 0)
			(layer "B.SilkS")
			(hide yes)
			(effects
				(font
					(size 1.27 1.27)
				)
				(justify mirror)
			)
		)
		(property "Value" ""
			(at 0 0 0)
			(layer "B.Fab")
			(effects
				(font
					(size 1.27 1.27)
				)
				(justify mirror)
			)
		)
		(duplicate_pad_numbers_are_jumpers no)
		(fp_line
			(start 0.299974 0.150114)
			(end 0.299974 -0.150114)
			(stroke
				(width 0.1)
				(type default)
			)
			(layer "B.Fab")
		)
		(fp_line
			(start 0.299974 -0.150114)
			(end -0.299974 -0.150114)
			(stroke
				(width 0.1)
				(type default)
			)
			(layer "B.Fab")
		)
		(fp_line
			(start -0.299974 0.150114)
			(end 0.299974 0.150114)
			(stroke
				(width 0.1)
				(type default)
			)
			(layer "B.Fab")
		)
		(fp_line
			(start -0.299974 -0.150114)
			(end -0.299974 0.150114)
			(stroke
				(width 0.1)
				(type default)
			)
			(layer "B.Fab")
		)
		(pad "1" smd rect
			(at 0.2667 0)
			(size 0.3048 0.381)
			(layers "B.Cu" "B.Mask" "B.Paste")
			(net "P1V25_PEX3")
		)
		(pad "2" smd rect
			(at -0.2667 0)
			(size 0.3048 0.381)
			(layers "B.Cu" "B.Mask" "B.Paste")
			(net "GND")
		)
	)
	(footprint ""
		(layer "B.Cu")
		(at 221.807278 -279.909524 -90)
		(property "Reference" "C4279"
			(at 0 0 90)
			(layer "B.SilkS")
			(hide yes)
			(effects
				(font
					(size 1.27 1.27)
				)
				(justify mirror)
			)
		)
		(property "Value" ""
			(at 0 0 90)
			(layer "B.Fab")
			(effects
				(font
					(size 1.27 1.27)
				)
				(justify mirror)
			)
		)
		(duplicate_pad_numbers_are_jumpers no)
		(fp_line
			(start -0.299974 0.150114)
			(end 0.299974 0.150114)
			(stroke
				(width 0.1)
				(type default)
			)
			(layer "B.Fab")
		)
		(fp_line
			(start 0.299974 0.150114)
			(end 0.299974 -0.150114)
			(stroke
				(width 0.1)
				(type default)
			)
			(layer "B.Fab")
		)
		(fp_line
			(start -0.299974 -0.150114)
			(end -0.299974 0.150114)
			(stroke
				(width 0.1)
				(type default)
			)
			(layer "B.Fab")
		)
		(fp_line
			(start 0.299974 -0.150114)
			(end -0.299974 -0.150114)
			(stroke
				(width 0.1)
				(type default)
			)
			(layer "B.Fab")
		)
		(pad "1" smd rect
			(at 0.2667 0 90)
			(size 0.3048 0.381)
			(layers "B.Cu" "B.Mask" "B.Paste")
			(net "P1V25_PEX1")
		)
		(pad "2" smd rect
			(at -0.2667 0 90)
			(size 0.3048 0.381)
			(layers "B.Cu" "B.Mask" "B.Paste")
			(net "GND")
		)
	)
	(footprint ""
		(layer "B.Cu")
		(at 345.321382 -284.796738 -90)
		(property "Reference" "PC143"
			(at 0 0 90)
			(layer "B.SilkS")
			(hide yes)
			(effects
				(font
					(size 1.27 1.27)
				)
				(justify mirror)
			)
		)
		(property "Value" ""
			(at 0 0 90)
			(layer "B.Fab")
			(effects
				(font
					(size 1.27 1.27)
				)
				(justify mirror)
			)
		)
		(duplicate_pad_numbers_are_jumpers no)
		(fp_line
			(start -1.524 0.762)
			(end 1.524 0.762)
			(stroke
				(width 0.1524)
				(type default)
			)
			(layer "B.SilkS")
		)
		(fp_line
			(start 1.524 0.762)
			(end 1.524 -0.762)
			(stroke
				(width 0.1524)
				(type default)
			)
			(layer "B.SilkS")
		)
		(fp_line
			(start -1.524 -0.762)
			(end -1.524 0.762)
			(stroke
				(width 0.1524)
				(type default)
			)
			(layer "B.SilkS")
		)
		(fp_line
			(start 1.524 -0.762)
			(end -1.524 -0.762)
			(stroke
				(width 0.1524)
				(type default)
			)
			(layer "B.SilkS")
		)
		(fp_line
			(start -1.1049 0.724916)
			(end -1.1049 -0.724916)
			(stroke
				(width 0.1)
				(type default)
			)
			(layer "B.Fab")
		)
		(fp_line
			(start 1.1049 0.724916)
			(end -1.1049 0.724916)
			(stroke
				(width 0.1)
				(type default)
			)
			(layer "B.Fab")
		)
		(fp_line
			(start -1.1049 -0.724916)
			(end 1.1049 -0.724916)
			(stroke
				(width 0.1)
				(type default)
			)
			(layer "B.Fab")
		)
		(fp_line
			(start 1.1049 -0.724916)
			(end 1.1049 0.724916)
			(stroke
				(width 0.1)
				(type default)
			)
			(layer "B.Fab")
		)
		(pad "1" smd rect
			(at 0.889 0 270)
			(size 1.016 1.27)
			(layers "B.Cu" "B.Mask" "B.Paste")
			(net "SW_P12V_P0V8_PEX2_FLT")
		)
		(pad "2" smd rect
			(at -0.889 0 270)
			(size 1.016 1.27)
			(layers "B.Cu" "B.Mask" "B.Paste")
			(net "GND")
		)
	)
)
